(kicad_pcb
	(version 20260206)
	(generator "pcbnew")
	(generator_version "10.0")
	(general
		(thickness 1.6)
		(legacy_teardrops no)
	)
	(paper "A4")
	(title_block
		(title "04192023_DAF0TMB3IC0_F0TG_MB_C_brd_V02_OCP.brd")
		(comment 1 "Grand Teton / footprints 2535-2540 of 8354")
	)
	(layers
		(0 "F.Cu" signal "TOP")
		(4 "In1.Cu" signal "GND")
		(6 "In2.Cu" signal "IN1")
		(8 "In3.Cu" signal "GND1")
		(10 "In4.Cu" signal "IN2")
		(12 "In5.Cu" signal "GND2")
		(14 "In6.Cu" signal "IN3")
		(16 "In7.Cu" signal "GND3")
		(18 "In8.Cu" signal "VCC")
		(20 "In9.Cu" signal "VCC1")
		(22 "In10.Cu" signal "GND4")
		(24 "In11.Cu" signal "IN4")
		(26 "In12.Cu" signal "GND5")
		(28 "In13.Cu" signal "IN5")
		(30 "In14.Cu" signal "GND6")
		(32 "In15.Cu" signal "IN6")
		(34 "In16.Cu" signal "GND7")
		(2 "B.Cu" signal "BOTTOM")
		(9 "F.Adhes" user "F.Adhesive")
		(11 "B.Adhes" user "B.Adhesive")
		(13 "F.Paste" user "Package Geometry/Pastemask Top")
		(15 "B.Paste" user "Package Geometry/Pastemask Bottom")
		(5 "F.SilkS" user "Ref Des/Silkscreen Top")
		(7 "B.SilkS" user "Ref Des/Silkscreen Bottom")
		(1 "F.Mask" user "Board Geometry/Soldermask Top")
		(3 "B.Mask" user "Board Geometry/Soldermask Bottom")
		(17 "Dwgs.User" user "User.Drawings")
		(19 "Cmts.User" user "User.Comments")
		(21 "Eco1.User" user "User.Eco1")
		(23 "Eco2.User" user "User.Eco2")
		(25 "Edge.Cuts" user "Board Geometry/Outline")
		(27 "Margin" user)
		(31 "F.CrtYd" user "Package Geometry/Place Bound Top")
		(29 "B.CrtYd" user "Package Geometry/Place Bound Bottom")
		(35 "F.Fab" user "Ref Des/Assembly Top")
		(33 "B.Fab" user "Ref Des/Assembly Bottom")
	)
	(footprint ""
		(layer "F.Cu")
		(at 419.10889 -109.231176 -90)
		(property "Reference" "R1487"
			(at 0 0 270)
			(layer "F.SilkS")
			(hide yes)
			(effects
				(font
					(size 1.27 1.27)
				)
			)
		)
		(property "Value" ""
			(at 0 0 270)
			(layer "F.Fab")
			(effects
				(font
					(size 1.27 1.27)
				)
			)
		)
		(duplicate_pad_numbers_are_jumpers no)
		(fp_line
			(start -0.7874 0.4064)
			(end -0.7874 -0.4064)
			(stroke
				(width 0.1524)
				(type default)
			)
			(layer "F.SilkS")
		)
		(fp_line
			(start 0.7874 0.4064)
			(end -0.7874 0.4064)
			(stroke
				(width 0.1524)
				(type default)
			)
			(layer "F.SilkS")
		)
		(fp_line
			(start -0.7874 -0.4064)
			(end 0.7874 -0.4064)
			(stroke
				(width 0.1524)
				(type default)
			)
			(layer "F.SilkS")
		)
		(fp_line
			(start 0.7874 -0.4064)
			(end 0.7874 0.4064)
			(stroke
				(width 0.1524)
				(type default)
			)
			(layer "F.SilkS")
		)
		(fp_line
			(start -0.67945 0.3048)
			(end -0.67945 -0.305054)
			(stroke
				(width 0.1)
				(type default)
			)
			(layer "F.Fab")
		)
		(fp_line
			(start -0.12065 0.3048)
			(end -0.67945 0.3048)
			(stroke
				(width 0.1)
				(type default)
			)
			(layer "F.Fab")
		)
		(fp_line
			(start 0.120396 0.3048)
			(end 0.120396 0.2794)
			(stroke
				(width 0.1)
				(type default)
			)
			(layer "F.Fab")
		)
		(fp_line
			(start 0.67945 0.3048)
			(end 0.120396 0.3048)
			(stroke
				(width 0.1)
				(type default)
			)
			(layer "F.Fab")
		)
		(fp_line
			(start -0.12065 0.2794)
			(end -0.12065 0.3048)
			(stroke
				(width 0.1)
				(type default)
			)
			(layer "F.Fab")
		)
		(fp_line
			(start 0.120396 0.2794)
			(end -0.12065 0.2794)
			(stroke
				(width 0.1)
				(type default)
			)
			(layer "F.Fab")
		)
		(fp_line
			(start -0.12065 -0.2794)
			(end 0.12065 -0.2794)
			(stroke
				(width 0.1)
				(type default)
			)
			(layer "F.Fab")
		)
		(fp_line
			(start 0.12065 -0.2794)
			(end 0.12065 -0.3048)
			(stroke
				(width 0.1)
				(type default)
			)
			(layer "F.Fab")
		)
		(fp_line
			(start 0.12065 -0.3048)
			(end 0.67945 -0.3048)
			(stroke
				(width 0.1)
				(type default)
			)
			(layer "F.Fab")
		)
		(fp_line
			(start 0.67945 -0.3048)
			(end 0.67945 0.3048)
			(stroke
				(width 0.1)
				(type default)
			)
			(layer "F.Fab")
		)
		(fp_line
			(start -0.67945 -0.305054)
			(end -0.12065 -0.305054)
			(stroke
				(width 0.1)
				(type default)
			)
			(layer "F.Fab")
		)
		(fp_line
			(start -0.12065 -0.305054)
			(end -0.12065 -0.2794)
			(stroke
				(width 0.1)
				(type default)
			)
			(layer "F.Fab")
		)
		(pad "1" smd circle
			(at -0.40005 0 270)
			(size 0 0)
			(layers "F.Cu" "F.Mask" "F.Paste")
			(net "P12V_OCP_SFF_BUF_EN_R")
		)
		(pad "2" smd circle
			(at 0.40005 0 270)
			(size 0 0)
			(layers "F.Cu" "F.Mask" "F.Paste")
			(net "P3V3_OCP_EN_1_R2")
		)
	)
	(footprint ""
		(layer "F.Cu")
		(at 186.038236 -428.414942 90)
		(property "Reference" "R3442"
			(at 0 0 90)
			(layer "F.SilkS")
			(hide yes)
			(effects
				(font
					(size 1.27 1.27)
				)
			)
		)
		(property "Value" ""
			(at 0 0 90)
			(layer "F.Fab")
			(effects
				(font
					(size 1.27 1.27)
				)
			)
		)
		(duplicate_pad_numbers_are_jumpers no)
		(fp_line
			(start 0.7874 -0.4064)
			(end 0.7874 0.4064)
			(stroke
				(width 0.1524)
				(type default)
			)
			(layer "F.SilkS")
		)
		(fp_line
			(start -0.7874 -0.4064)
			(end 0.7874 -0.4064)
			(stroke
				(width 0.1524)
				(type default)
			)
			(layer "F.SilkS")
		)
		(fp_line
			(start 0.7874 0.4064)
			(end -0.7874 0.4064)
			(stroke
				(width 0.1524)
				(type default)
			)
			(layer "F.SilkS")
		)
		(fp_line
			(start -0.7874 0.4064)
			(end -0.7874 -0.4064)
			(stroke
				(width 0.1524)
				(type default)
			)
			(layer "F.SilkS")
		)
		(fp_line
			(start -0.12065 -0.305054)
			(end -0.12065 -0.2794)
			(stroke
				(width 0.1)
				(type default)
			)
			(layer "F.Fab")
		)
		(fp_line
			(start -0.67945 -0.305054)
			(end -0.12065 -0.305054)
			(stroke
				(width 0.1)
				(type default)
			)
			(layer "F.Fab")
		)
		(fp_line
			(start 0.67945 -0.3048)
			(end 0.67945 0.3048)
			(stroke
				(width 0.1)
				(type default)
			)
			(layer "F.Fab")
		)
		(fp_line
			(start 0.12065 -0.3048)
			(end 0.67945 -0.3048)
			(stroke
				(width 0.1)
				(type default)
			)
			(layer "F.Fab")
		)
		(fp_line
			(start 0.12065 -0.2794)
			(end 0.12065 -0.3048)
			(stroke
				(width 0.1)
				(type default)
			)
			(layer "F.Fab")
		)
		(fp_line
			(start -0.12065 -0.2794)
			(end 0.12065 -0.2794)
			(stroke
				(width 0.1)
				(type default)
			)
			(layer "F.Fab")
		)
		(fp_line
			(start 0.120396 0.2794)
			(end -0.12065 0.2794)
			(stroke
				(width 0.1)
				(type default)
			)
			(layer "F.Fab")
		)
		(fp_line
			(start -0.12065 0.2794)
			(end -0.12065 0.3048)
			(stroke
				(width 0.1)
				(type default)
			)
			(layer "F.Fab")
		)
		(fp_line
			(start 0.67945 0.3048)
			(end 0.120396 0.3048)
			(stroke
				(width 0.1)
				(type default)
			)
			(layer "F.Fab")
		)
		(fp_line
			(start 0.120396 0.3048)
			(end 0.120396 0.2794)
			(stroke
				(width 0.1)
				(type default)
			)
			(layer "F.Fab")
		)
		(fp_line
			(start -0.12065 0.3048)
			(end -0.67945 0.3048)
			(stroke
				(width 0.1)
				(type default)
			)
			(layer "F.Fab")
		)
		(fp_line
			(start -0.67945 0.3048)
			(end -0.67945 -0.305054)
			(stroke
				(width 0.1)
				(type default)
			)
			(layer "F.Fab")
		)
		(pad "1" smd circle
			(at -0.40005 0 90)
			(size 0 0)
			(layers "F.Cu" "F.Mask" "F.Paste")
			(net "GPU_PEX_STRAP0")
		)
		(pad "2" smd circle
			(at 0.40005 0 90)
			(size 0 0)
			(layers "F.Cu" "F.Mask" "F.Paste")
			(net "GND")
		)
	)
	(footprint ""
		(layer "F.Cu")
		(at 307.404516 -435.720744 90)
		(property "Reference" "C1976"
			(at 0 0 90)
			(layer "F.SilkS")
			(hide yes)
			(effects
				(font
					(size 1.27 1.27)
				)
			)
		)
		(property "Value" ""
			(at 0 0 90)
			(layer "F.Fab")
			(effects
				(font
					(size 1.27 1.27)
				)
			)
		)
		(duplicate_pad_numbers_are_jumpers no)
		(fp_line
			(start 0.7874 -0.4064)
			(end 0.7874 0.4064)
			(stroke
				(width 0.1524)
				(type default)
			)
			(layer "F.SilkS")
		)
		(fp_line
			(start -0.7874 -0.4064)
			(end 0.7874 -0.4064)
			(stroke
				(width 0.1524)
				(type default)
			)
			(layer "F.SilkS")
		)
		(fp_line
			(start 0.7874 0.4064)
			(end -0.7874 0.4064)
			(stroke
				(width 0.1524)
				(type default)
			)
			(layer "F.SilkS")
		)
		(fp_line
			(start -0.7874 0.4064)
			(end -0.7874 -0.4064)
			(stroke
				(width 0.1524)
				(type default)
			)
			(layer "F.SilkS")
		)
		(fp_line
			(start -0.12065 -0.305054)
			(end -0.12065 -0.2794)
			(stroke
				(width 0.1)
				(type default)
			)
			(layer "F.Fab")
		)
		(fp_line
			(start -0.67945 -0.305054)
			(end -0.12065 -0.305054)
			(stroke
				(width 0.1)
				(type default)
			)
			(layer "F.Fab")
		)
		(fp_line
			(start 0.67945 -0.3048)
			(end 0.67945 0.3048)
			(stroke
				(width 0.1)
				(type default)
			)
			(layer "F.Fab")
		)
		(fp_line
			(start 0.12065 -0.3048)
			(end 0.67945 -0.3048)
			(stroke
				(width 0.1)
				(type default)
			)
			(layer "F.Fab")
		)
		(fp_line
			(start 0.12065 -0.2794)
			(end 0.12065 -0.3048)
			(stroke
				(width 0.1)
				(type default)
			)
			(layer "F.Fab")
		)
		(fp_line
			(start -0.12065 -0.2794)
			(end 0.12065 -0.2794)
			(stroke
				(width 0.1)
				(type default)
			)
			(layer "F.Fab")
		)
		(fp_line
			(start 0.120396 0.2794)
			(end -0.12065 0.2794)
			(stroke
				(width 0.1)
				(type default)
			)
			(layer "F.Fab")
		)
		(fp_line
			(start -0.12065 0.2794)
			(end -0.12065 0.3048)
			(stroke
				(width 0.1)
				(type default)
			)
			(layer "F.Fab")
		)
		(fp_line
			(start 0.67945 0.3048)
			(end 0.120396 0.3048)
			(stroke
				(width 0.1)
				(type default)
			)
			(layer "F.Fab")
		)
		(fp_line
			(start 0.120396 0.3048)
			(end 0.120396 0.2794)
			(stroke
				(width 0.1)
				(type default)
			)
			(layer "F.Fab")
		)
		(fp_line
			(start -0.12065 0.3048)
			(end -0.67945 0.3048)
			(stroke
				(width 0.1)
				(type default)
			)
			(layer "F.Fab")
		)
		(fp_line
			(start -0.67945 0.3048)
			(end -0.67945 -0.305054)
			(stroke
				(width 0.1)
				(type default)
			)
			(layer "F.Fab")
		)
		(pad "1" smd circle
			(at -0.40005 0 90)
			(size 0 0)
			(layers "F.Cu" "F.Mask" "F.Paste")
			(net "GPU_FPGA_OVERT_ISO_N")
		)
		(pad "2" smd circle
			(at 0.40005 0 90)
			(size 0 0)
			(layers "F.Cu" "F.Mask" "F.Paste")
			(net "GND")
		)
	)
	(footprint ""
		(layer "F.Cu")
		(at 138.617198 -167.510206 180)
		(property "Reference" "PR164"
			(at 0 0 180)
			(layer "F.SilkS")
			(hide yes)
			(effects
				(font
					(size 1.27 1.27)
				)
			)
		)
		(property "Value" ""
			(at 0 0 180)
			(layer "F.Fab")
			(effects
				(font
					(size 1.27 1.27)
				)
			)
		)
		(duplicate_pad_numbers_are_jumpers no)
		(fp_line
			(start 0.7874 0.4064)
			(end -0.7874 0.4064)
			(stroke
				(width 0.1524)
				(type default)
			)
			(layer "F.SilkS")
		)
		(fp_line
			(start 0.7874 -0.4064)
			(end 0.7874 0.4064)
			(stroke
				(width 0.1524)
				(type default)
			)
			(layer "F.SilkS")
		)
		(fp_line
			(start -0.7874 0.4064)
			(end -0.7874 -0.4064)
			(stroke
				(width 0.1524)
				(type default)
			)
			(layer "F.SilkS")
		)
		(fp_line
			(start -0.7874 -0.4064)
			(end 0.7874 -0.4064)
			(stroke
				(width 0.1524)
				(type default)
			)
			(layer "F.SilkS")
		)
		(fp_line
			(start 0.67945 0.3048)
			(end 0.120396 0.3048)
			(stroke
				(width 0.1)
				(type default)
			)
			(layer "F.Fab")
		)
		(fp_line
			(start 0.67945 -0.3048)
			(end 0.67945 0.3048)
			(stroke
				(width 0.1)
				(type default)
			)
			(layer "F.Fab")
		)
		(fp_line
			(start 0.12065 -0.2794)
			(end 0.12065 -0.3048)
			(stroke
				(width 0.1)
				(type default)
			)
			(layer "F.Fab")
		)
		(fp_line
			(start 0.12065 -0.3048)
			(end 0.67945 -0.3048)
			(stroke
				(width 0.1)
				(type default)
			)
			(layer "F.Fab")
		)
		(fp_line
			(start 0.120396 0.3048)
			(end 0.120396 0.2794)
			(stroke
				(width 0.1)
				(type default)
			)
			(layer "F.Fab")
		)
		(fp_line
			(start 0.120396 0.2794)
			(end -0.12065 0.2794)
			(stroke
				(width 0.1)
				(type default)
			)
			(layer "F.Fab")
		)
		(fp_line
			(start -0.12065 0.3048)
			(end -0.67945 0.3048)
			(stroke
				(width 0.1)
				(type default)
			)
			(layer "F.Fab")
		)
		(fp_line
			(start -0.12065 0.2794)
			(end -0.12065 0.3048)
			(stroke
				(width 0.1)
				(type default)
			)
			(layer "F.Fab")
		)
		(fp_line
			(start -0.12065 -0.2794)
			(end 0.12065 -0.2794)
			(stroke
				(width 0.1)
				(type default)
			)
			(layer "F.Fab")
		)
		(fp_line
			(start -0.12065 -0.305054)
			(end -0.12065 -0.2794)
			(stroke
				(width 0.1)
				(type default)
			)
			(layer "F.Fab")
		)
		(fp_line
			(start -0.67945 0.3048)
			(end -0.67945 -0.305054)
			(stroke
				(width 0.1)
				(type default)
			)
			(layer "F.Fab")
		)
		(fp_line
			(start -0.67945 -0.305054)
			(end -0.12065 -0.305054)
			(stroke
				(width 0.1)
				(type default)
			)
			(layer "F.Fab")
		)
		(pad "1" smd circle
			(at -0.40005 0 180)
			(size 0 0)
			(layers "F.Cu" "F.Mask" "F.Paste")
			(net "VSENSE_VSS_SENSE_A_P1")
		)
		(pad "2" smd circle
			(at 0.40005 0 180)
			(size 0 0)
			(layers "F.Cu" "F.Mask" "F.Paste")
			(net "GND")
		)
	)
	(footprint ""
		(layer "F.Cu")
		(at 167.871902 -439.490358)
		(property "Reference" "Q67"
			(at 3.377184 1.185672 0)
			(unlocked yes)
			(layer "F.SilkS")
			(effects
				(font
					(size 0.7874 0.5842)
					(thickness 0.1524)
				)
				(justify left)
			)
		)
		(property "Value" ""
			(at 0 0 0)
			(layer "F.Fab")
			(effects
				(font
					(size 1.27 1.27)
				)
			)
		)
		(duplicate_pad_numbers_are_jumpers no)
		(fp_line
			(start -1.332738 -1.100074)
			(end -0.4826 -1.100074)
			(stroke
				(width 0.1524)
				(type default)
			)
			(layer "F.SilkS")
		)
		(fp_line
			(start -1.332738 1.100074)
			(end -1.332738 -1.100074)
			(stroke
				(width 0.1524)
				(type default)
			)
			(layer "F.SilkS")
		)
		(fp_line
			(start -0.4826 -1.100074)
			(end 0 -0.541274)
			(stroke
				(width 0.1524)
				(type default)
			)
			(layer "F.SilkS")
		)
		(fp_line
			(start 0 -0.541274)
			(end 0.4826 -1.100074)
			(stroke
				(width 0.1524)
				(type default)
			)
			(layer "F.SilkS")
		)
		(fp_line
			(start 0.4826 -1.100074)
			(end 1.332738 -1.100074)
			(stroke
				(width 0.1524)
				(type default)
			)
			(layer "F.SilkS")
		)
		(fp_line
			(start 1.332738 -1.100074)
			(end 1.332738 1.100074)
			(stroke
				(width 0.1524)
				(type default)
			)
			(layer "F.SilkS")
		)
		(fp_line
			(start 1.332738 1.100074)
			(end -1.332738 1.100074)
			(stroke
				(width 0.1524)
				(type default)
			)
			(layer "F.SilkS")
		)
		(fp_poly
			(pts
				(xy -1.561592 -1.409192) (xy -2.337308 -1.52908) (xy -1.930908 -2.101596)
			)
			(stroke
				(width 0)
				(type default)
			)
			(fill yes)
			(layer "F.SilkS")
		)
		(fp_line
			(start -0.674878 -1.100074)
			(end 0.674878 -1.100074)
			(stroke
				(width 0.1)
				(type default)
			)
			(layer "F.Fab")
		)
		(fp_line
			(start -0.674878 1.100074)
			(end -0.674878 -1.100074)
			(stroke
				(width 0.1)
				(type default)
			)
			(layer "F.Fab")
		)
		(fp_line
			(start 0.674878 -1.100074)
			(end 0.674878 1.100074)
			(stroke
				(width 0.1)
				(type default)
			)
			(layer "F.Fab")
		)
		(fp_line
			(start 0.674878 1.100074)
			(end -0.674878 1.100074)
			(stroke
				(width 0.1)
				(type default)
			)
			(layer "F.Fab")
		)
		(fp_poly
			(pts
				(xy -2.2352 -0.298958) (xy -2.2352 -1.001014) (xy -1.533144 -0.649986)
			)
			(stroke
				(width 0)
				(type default)
			)
			(fill yes)
			(layer "F.Fab")
		)
		(pad "1" smd rect
			(at -0.94996 -0.649986 90)
			(size 0.4318 0.508)
			(layers "F.Cu" "F.Mask" "F.Paste")
			(net "GND")
		)
		(pad "2" smd rect
			(at -0.94996 0 90)
			(size 0.4318 0.508)
			(layers "F.Cu" "F.Mask" "F.Paste")
			(net "BIC_MONITER")
		)
		(pad "3" smd rect
			(at -0.94996 0.649986 90)
			(size 0.4318 0.508)
			(layers "F.Cu" "F.Mask" "F.Paste")
			(net "BIC_MONITER_ISO")
		)
		(pad "4" smd rect
			(at 0.94996 0.649986 90)
			(size 0.4318 0.508)
			(layers "F.Cu" "F.Mask" "F.Paste")
			(net "GND")
		)
		(pad "5" smd rect
			(at 0.94996 0 90)
			(size 0.4318 0.508)
			(layers "F.Cu" "F.Mask" "F.Paste")
			(net "BIC_MONITER_N")
		)
		(pad "6" smd rect
			(at 0.94996 -0.649986 90)
			(size 0.4318 0.508)
			(layers "F.Cu" "F.Mask" "F.Paste")
			(net "BIC_MONITER_N")
		)
	)
	(footprint ""
		(layer "F.Cu")
		(at 407.1874 -76.063348)
		(property "Reference" "U236"
			(at -3.0988 -2.885948 0)
			(unlocked yes)
			(layer "F.SilkS")
			(effects
				(font
					(size 0.7874 0.5842)
					(thickness 0.1524)
				)
				(justify left)
			)
		)
		(property "Value" ""
			(at 0 0 0)
			(layer "F.Fab")
			(effects
				(font
					(size 1.27 1.27)
				)
			)
		)
		(duplicate_pad_numbers_are_jumpers no)
		(fp_line
			(start -1.463548 -1.549908)
			(end -0.787908 -1.549908)
			(stroke
				(width 0.1524)
				(type default)
			)
			(layer "F.SilkS")
		)
		(fp_line
			(start -1.463548 1.549908)
			(end -1.463548 -1.549908)
			(stroke
				(width 0.1524)
				(type default)
			)
			(layer "F.SilkS")
		)
		(fp_line
			(start -0.787908 -1.549908)
			(end -0.0254 -0.7874)
			(stroke
				(width 0.1524)
				(type default)
			)
			(layer "F.SilkS")
		)
		(fp_line
			(start -0.0254 1.549908)
			(end -1.463548 1.549908)
			(stroke
				(width 0.1524)
				(type default)
			)
			(layer "F.SilkS")
		)
		(fp_line
			(start 1.0922 -1.549908)
			(end 1.463548 -1.549908)
			(stroke
				(width 0.1524)
				(type default)
			)
			(layer "F.SilkS")
		)
		(fp_line
			(start 1.463548 -1.549908)
			(end 1.463548 1.549908)
			(stroke
				(width 0.1524)
				(type default)
			)
			(layer "F.SilkS")
		)
		(fp_line
			(start 1.463548 1.549908)
			(end 1.0922 1.549908)
			(stroke
				(width 0.1524)
				(type default)
			)
			(layer "F.SilkS")
		)
		(fp_poly
			(pts
				(xy -2.623566 -2.194306) (xy -2.00406 -2.205482) (xy -2.30251 -1.580134)
			)
			(stroke
				(width 0)
				(type default)
			)
			(fill yes)
			(layer "F.SilkS")
		)
		(fp_line
			(start -1.549908 -1.549908)
			(end 1.549908 -1.549908)
			(stroke
				(width 0.1)
				(type default)
			)
			(layer "F.Fab")
		)
		(fp_line
			(start -1.549908 1.549908)
			(end -1.549908 -1.549908)
			(stroke
				(width 0.1)
				(type default)
			)
			(layer "F.Fab")
		)
		(fp_line
			(start 1.549908 -1.549908)
			(end 1.549908 1.549908)
			(stroke
				(width 0.1)
				(type default)
			)
			(layer "F.Fab")
		)
		(fp_line
			(start 1.549908 1.549908)
			(end -1.549908 1.549908)
			(stroke
				(width 0.1)
				(type default)
			)
			(layer "F.Fab")
		)
		(fp_poly
			(pts
				(xy -3.4798 -1.359916) (xy -2.86004 -1.050036) (xy -3.4798 -0.740156)
			)
			(stroke
				(width 0)
				(type default)
			)
			(fill yes)
			(layer "F.Fab")
		)
		(pad "1" smd rect
			(at -2.175002 -1.050036 90)
			(size 0.6096 1.1684)
			(layers "F.Cu" "F.Mask" "F.Paste")
			(net "P3V3_AUX")
		)
		(pad "2" smd rect
			(at -2.175002 -0.32512 90)
			(size 0.4318 1.1684)
			(layers "F.Cu" "F.Mask" "F.Paste")
			(net "SMB_OCP_SFF_3V3AUX_SCL")
		)
		(pad "3" smd rect
			(at -2.175002 0.32512 90)
			(size 0.4318 1.1684)
			(layers "F.Cu" "F.Mask" "F.Paste")
			(net "SMB_OCP_SFF_3V3AUX_SDA")
		)
		(pad "4" smd rect
			(at -2.175002 1.050036 90)
			(size 0.6096 1.1684)
			(layers "F.Cu" "F.Mask" "F.Paste")
			(net "GND")
		)
		(pad "5" smd rect
			(at 2.175002 1.050036 90)
			(size 0.6096 1.1684)
			(layers "F.Cu" "F.Mask" "F.Paste")
			(net "HP_LVC3_OCP_V3_1_R_EN")
		)
		(pad "6" smd rect
			(at 2.175002 0.32512 90)
			(size 0.4318 1.1684)
			(layers "F.Cu" "F.Mask" "F.Paste")
			(net "SMB_OCP_SFF_3V3AUX_BUF_SDA")
		)
		(pad "7" smd rect
			(at 2.175002 -0.32512 90)
			(size 0.4318 1.1684)
			(layers "F.Cu" "F.Mask" "F.Paste")
			(net "SMB_OCP_SFF_3V3AUX_BUF_SCL")
		)
		(pad "8" smd rect
			(at 2.175002 -1.050036 90)
			(size 0.6096 1.1684)
			(layers "F.Cu" "F.Mask" "F.Paste")
			(net "P3V3_OCP_SFF")
		)
	)
)
